# T6G (Grand Teton) — schematic netlist excerpt (pin names and nets, part order shuffled) for the footprints in the layout excerpt that follows; sources: Cadence DE-HDL packaged netlist, KiCad conversion of 04192023_DAF0TMB3IC0_F0TG_MB_C_brd_V02_OCP.brd

PU6510  ISL69260IRAZT  ISL69260IRAZ-T IC  pkg QFN40_TH_0-4_5X5XE  page 364
  PWM0  = NC_P0V9_RETIMER_CPU1_PWM8
  PWM1  = NC_P0V9_RETIMER_CPU1_PWM7
  PWM2  = NC_P0V9_RETIMER_CPU1_PWM6
  PWM3  = NC_P0V9_RETIMER_CPU1_PWM5
  PWM4  = NC_P0V9_RETIMER_CPU1_PWM4
  PWM5  = NC_P0V9_RETIMER_CPU1_PWM3
  PWM6  = P0V9_RETIMER_CPU1_PWM2
  PWM7  = P0V9_RETIMER_CPU1_PWM1
  PMSDA  = P0V9_RETIMER_CPU1_PMSDA_R
  PMSCL  = P0V9_RETIMER_CPU1_PMSCL_R
  \npmalert#\  = TP_P0V9_RETIMER_CPU1_PMALERT
  PG0  = PWRGD_P0V9_RETIMER_CPU1_R
  EN0  = P0V9_RETIMER_CPU1_EN0_R
  \nvrhot#\  = P0V9_RETIMER_CPU1_VRHOT
  \npinalert#||npsyscrit#\  = P0V9_RETIMER_CPU1_INALERT
  PG1  = NC_P0V9_RETIMER_CPU1_PG1
  SVCLK  = P0V9_RETIMER_CPU1_SVID_CLK
  SVDATA  = P0V9_RETIMER_CPU1_SVID_SDA
  \nsvalert#\  = TP_P0V9_RETIMER_CPU1_SVID_ALERT_N
  EN1  = P0V9_RETIMER_CPU1_EN1_R
  VSEN0  = P0V9_RETIMER_CPU1_SENSE_R_P
  RGND0  = P0V9_RETIMER_CPU1_SENSE_SH_N
  CS7  = P0V9_RETIMER_CPU1_IMON1
  CS6  = P0V9_RETIMER_CPU1_IMON2
  CS5  = NC_P0V9_RETIMER_CPU1_IMON3
  CS4  = NC_P0V9_RETIMER_CPU1_IMON4
  CS3  = NC_P0V9_RETIMER_CPU1_IMON5
  CS2  = NC_P0V9_RETIMER_CPU1_IMON6
  CS1  = NC_P0V9_RETIMER_CPU1_IMON7
  CS0  = NC_P0V9_RETIMER_CPU1_IMON8
  RGND1  = GND
  VSEN1  = GND
  CFP  = P0V9_RETIMER_CPU1_CFP
  ADDR_CFG  = P0V9_RETIMER_CPU1_ADDR
  TEMP0  = P0V9_RETIMER_CPU1_TEMP0
  \temp1||isys\  = P0V9_RETIMER_CPU1_TEMP1_R
  \vmon||iinsen||vsys||isys\  = P0V9_RETIMER_CPU1_VMON
  \vinsen||vsys\  = P0V9_RETIMER_CPU1_VINSEN
  VCC  = P0V9_RETIMER_CPU1_VCC
  VCCS  = PV09_RETIMER_CPU1_VCCS
  TH_GND  = GND

(kicad_pcb
	(version 20260206)
	(generator "pcbnew")
	(generator_version "10.0")
	(general
		(thickness 1.6)
		(legacy_teardrops no)
	)
	(paper "A4")
	(title_block
		(title "04192023_DAF0TMB3IC0_F0TG_MB_C_brd_V02_OCP.brd")
		(comment 1 "Grand Teton / footprint 4353 of 8354 (PU6510), pads 1-41 of 41")
	)
	(layers
		(0 "F.Cu" signal "TOP")
		(4 "In1.Cu" signal "GND")
		(6 "In2.Cu" signal "IN1")
		(8 "In3.Cu" signal "GND1")
		(10 "In4.Cu" signal "IN2")
		(12 "In5.Cu" signal "GND2")
		(14 "In6.Cu" signal "IN3")
		(16 "In7.Cu" signal "GND3")
		(18 "In8.Cu" signal "VCC")
		(20 "In9.Cu" signal "VCC1")
		(22 "In10.Cu" signal "GND4")
		(24 "In11.Cu" signal "IN4")
		(26 "In12.Cu" signal "GND5")
		(28 "In13.Cu" signal "IN5")
		(30 "In14.Cu" signal "GND6")
		(32 "In15.Cu" signal "IN6")
		(34 "In16.Cu" signal "GND7")
		(2 "B.Cu" signal "BOTTOM")
		(9 "F.Adhes" user "F.Adhesive")
		(11 "B.Adhes" user "B.Adhesive")
		(13 "F.Paste" user "Package Geometry/Pastemask Top")
		(15 "B.Paste" user "Package Geometry/Pastemask Bottom")
		(5 "F.SilkS" user "Ref Des/Silkscreen Top")
		(7 "B.SilkS" user "Ref Des/Silkscreen Bottom")
		(1 "F.Mask" user "Board Geometry/Soldermask Top")
		(3 "B.Mask" user "Board Geometry/Soldermask Bottom")
		(17 "Dwgs.User" user "User.Drawings")
		(19 "Cmts.User" user "User.Comments")
		(21 "Eco1.User" user "User.Eco1")
		(23 "Eco2.User" user "User.Eco2")
		(25 "Edge.Cuts" user "Board Geometry/Outline")
		(27 "Margin" user)
		(31 "F.CrtYd" user "Package Geometry/Place Bound Top")
		(29 "B.CrtYd" user "Package Geometry/Place Bound Bottom")
		(35 "F.Fab" user "Ref Des/Assembly Top")
		(33 "B.Fab" user "Ref Des/Assembly Bottom")
	)
	(footprint ""
		(layer "F.Cu")
		(at 15.180818 -410.31287 90)
		(property "Reference" "PU6510"
			(at -3.06324 -7.03707 90)
			(unlocked yes)
			(layer "F.SilkS")
			(effects
				(font
					(size 0.7874 0.5842)
					(thickness 0.1524)
				)
				(justify left)
			)
		)
		(property "Value" ""
			(at 0 0 90)
			(layer "F.Fab")
			(effects
				(font
					(size 1.27 1.27)
				)
			)
		)
		(duplicate_pad_numbers_are_jumpers no)
		(pad "1" smd rect
			(at -2.400046 -1.800098)
			(size 0.1778 0.6096)
			(layers "F.Cu" "F.Mask" "F.Paste")
			(net "NC_P0V9_RETIMER_CPU1_PWM8")
		)
		(pad "2" smd rect
			(at -2.400046 -1.400048)
			(size 0.1778 0.6096)
			(layers "F.Cu" "F.Mask" "F.Paste")
			(net "NC_P0V9_RETIMER_CPU1_PWM7")
		)
		(pad "3" smd rect
			(at -2.400046 -0.999998)
			(size 0.1778 0.6096)
			(layers "F.Cu" "F.Mask" "F.Paste")
			(net "NC_P0V9_RETIMER_CPU1_PWM6")
		)
		(pad "4" smd rect
			(at -2.400046 -0.599948)
			(size 0.1778 0.6096)
			(layers "F.Cu" "F.Mask" "F.Paste")
			(net "NC_P0V9_RETIMER_CPU1_PWM5")
		)
		(pad "5" smd rect
			(at -2.400046 -0.199898)
			(size 0.1778 0.6096)
			(layers "F.Cu" "F.Mask" "F.Paste")
			(net "NC_P0V9_RETIMER_CPU1_PWM4")
		)
		(pad "6" smd rect
			(at -2.400046 0.199898)
			(size 0.1778 0.6096)
			(layers "F.Cu" "F.Mask" "F.Paste")
			(net "NC_P0V9_RETIMER_CPU1_PWM3")
		)
		(pad "7" smd rect
			(at -2.400046 0.599948)
			(size 0.1778 0.6096)
			(layers "F.Cu" "F.Mask" "F.Paste")
			(net "P0V9_RETIMER_CPU1_PWM2")
		)
		(pad "8" smd rect
			(at -2.400046 0.999998)
			(size 0.1778 0.6096)
			(layers "F.Cu" "F.Mask" "F.Paste")
			(net "P0V9_RETIMER_CPU1_PWM1")
		)
		(pad "9" smd rect
			(at -2.400046 1.400048)
			(size 0.1778 0.6096)
			(layers "F.Cu" "F.Mask" "F.Paste")
			(net "P0V9_RETIMER_CPU1_PMSDA_R")
		)
		(pad "10" smd rect
			(at -2.400046 1.800098)
			(size 0.1778 0.6096)
			(layers "F.Cu" "F.Mask" "F.Paste")
			(net "P0V9_RETIMER_CPU1_PMSCL_R")
		)
		(pad "11" smd rect
			(at -1.800098 2.400046 90)
			(size 0.1778 0.6096)
			(layers "F.Cu" "F.Mask" "F.Paste")
			(net "TP_P0V9_RETIMER_CPU1_PMALERT")
		)
		(pad "12" smd rect
			(at -1.400048 2.400046 90)
			(size 0.1778 0.6096)
			(layers "F.Cu" "F.Mask" "F.Paste")
			(net "PWRGD_P0V9_RETIMER_CPU1_R")
		)
		(pad "13" smd rect
			(at -0.999998 2.400046 90)
			(size 0.1778 0.6096)
			(layers "F.Cu" "F.Mask" "F.Paste")
			(net "P0V9_RETIMER_CPU1_EN0_R")
		)
		(pad "14" smd rect
			(at -0.599948 2.400046 90)
			(size 0.1778 0.6096)
			(layers "F.Cu" "F.Mask" "F.Paste")
			(net "P0V9_RETIMER_CPU1_VRHOT")
		)
		(pad "15" smd rect
			(at -0.199898 2.400046 90)
			(size 0.1778 0.6096)
			(layers "F.Cu" "F.Mask" "F.Paste")
			(net "P0V9_RETIMER_CPU1_INALERT")
		)
		(pad "16" smd rect
			(at 0.199898 2.400046 90)
			(size 0.1778 0.6096)
			(layers "F.Cu" "F.Mask" "F.Paste")
			(net "NC_P0V9_RETIMER_CPU1_PG1")
		)
		(pad "17" smd rect
			(at 0.599948 2.400046 90)
			(size 0.1778 0.6096)
			(layers "F.Cu" "F.Mask" "F.Paste")
			(net "P0V9_RETIMER_CPU1_SVID_CLK")
		)
		(pad "18" smd rect
			(at 0.999998 2.400046 90)
			(size 0.1778 0.6096)
			(layers "F.Cu" "F.Mask" "F.Paste")
			(net "P0V9_RETIMER_CPU1_SVID_SDA")
		)
		(pad "19" smd rect
			(at 1.400048 2.400046 90)
			(size 0.1778 0.6096)
			(layers "F.Cu" "F.Mask" "F.Paste")
			(net "TP_P0V9_RETIMER_CPU1_SVID_ALERT_N")
		)
		(pad "20" smd rect
			(at 1.800098 2.400046 90)
			(size 0.1778 0.6096)
			(layers "F.Cu" "F.Mask" "F.Paste")
			(net "P0V9_RETIMER_CPU1_EN1_R")
		)
		(pad "21" smd rect
			(at 2.400046 1.800098)
			(size 0.1778 0.6096)
			(layers "F.Cu" "F.Mask" "F.Paste")
			(net "P0V9_RETIMER_CPU1_SENSE_R_P")
		)
		(pad "22" smd rect
			(at 2.400046 1.400048)
			(size 0.1778 0.6096)
			(layers "F.Cu" "F.Mask" "F.Paste")
			(net "P0V9_RETIMER_CPU1_SENSE_SH_N")
		)
		(pad "23" smd rect
			(at 2.400046 0.999998)
			(size 0.1778 0.6096)
			(layers "F.Cu" "F.Mask" "F.Paste")
			(net "P0V9_RETIMER_CPU1_IMON1")
		)
		(pad "24" smd rect
			(at 2.400046 0.599948)
			(size 0.1778 0.6096)
			(layers "F.Cu" "F.Mask" "F.Paste")
			(net "P0V9_RETIMER_CPU1_IMON2")
		)
		(pad "25" smd rect
			(at 2.400046 0.199898)
			(size 0.1778 0.6096)
			(layers "F.Cu" "F.Mask" "F.Paste")
			(net "NC_P0V9_RETIMER_CPU1_IMON3")
		)
		(pad "26" smd rect
			(at 2.400046 -0.199898)
			(size 0.1778 0.6096)
			(layers "F.Cu" "F.Mask" "F.Paste")
			(net "NC_P0V9_RETIMER_CPU1_IMON4")
		)
		(pad "27" smd rect
			(at 2.400046 -0.599948)
			(size 0.1778 0.6096)
			(layers "F.Cu" "F.Mask" "F.Paste")
			(net "NC_P0V9_RETIMER_CPU1_IMON5")
		)
		(pad "28" smd rect
			(at 2.400046 -0.999998)
			(size 0.1778 0.6096)
			(layers "F.Cu" "F.Mask" "F.Paste")
			(net "NC_P0V9_RETIMER_CPU1_IMON6")
		)
		(pad "29" smd rect
			(at 2.400046 -1.400048)
			(size 0.1778 0.6096)
			(layers "F.Cu" "F.Mask" "F.Paste")
			(net "NC_P0V9_RETIMER_CPU1_IMON7")
		)
		(pad "30" smd rect
			(at 2.400046 -1.800098)
			(size 0.1778 0.6096)
			(layers "F.Cu" "F.Mask" "F.Paste")
			(net "NC_P0V9_RETIMER_CPU1_IMON8")
		)
		(pad "31" smd rect
			(at 1.800098 -2.400046 90)
			(size 0.1778 0.6096)
			(layers "F.Cu" "F.Mask" "F.Paste")
			(net "GND")
		)
		(pad "32" smd rect
			(at 1.400048 -2.400046 90)
			(size 0.1778 0.6096)
			(layers "F.Cu" "F.Mask" "F.Paste")
			(net "GND")
		)
		(pad "33" smd rect
			(at 0.999998 -2.400046 90)
			(size 0.1778 0.6096)
			(layers "F.Cu" "F.Mask" "F.Paste")
			(net "P0V9_RETIMER_CPU1_CFP")
		)
		(pad "34" smd rect
			(at 0.599948 -2.400046 90)
			(size 0.1778 0.6096)
			(layers "F.Cu" "F.Mask" "F.Paste")
			(net "P0V9_RETIMER_CPU1_ADDR")
		)
		(pad "35" smd rect
			(at 0.199898 -2.400046 90)
			(size 0.1778 0.6096)
			(layers "F.Cu" "F.Mask" "F.Paste")
			(net "P0V9_RETIMER_CPU1_TEMP0")
		)
		(pad "36" smd rect
			(at -0.199898 -2.400046 90)
			(size 0.1778 0.6096)
			(layers "F.Cu" "F.Mask" "F.Paste")
			(net "P0V9_RETIMER_CPU1_TEMP1_R")
		)
		(pad "37" smd rect
			(at -0.599948 -2.400046 90)
			(size 0.1778 0.6096)
			(layers "F.Cu" "F.Mask" "F.Paste")
			(net "P0V9_RETIMER_CPU1_VMON")
		)
		(pad "38" smd rect
			(at -0.999998 -2.400046 90)
			(size 0.1778 0.6096)
			(layers "F.Cu" "F.Mask" "F.Paste")
			(net "P0V9_RETIMER_CPU1_VINSEN")
		)
		(pad "39" smd rect
			(at -1.400048 -2.400046 90)
			(size 0.1778 0.6096)
			(layers "F.Cu" "F.Mask" "F.Paste")
			(net "P0V9_RETIMER_CPU1_VCC")
		)
		(pad "40" smd rect
			(at -1.800098 -2.400046 90)
			(size 0.1778 0.6096)
			(layers "F.Cu" "F.Mask" "F.Paste")
			(net "PV09_RETIMER_CPU1_VCCS")
		)
		(pad "TH" smd rect
			(at 0 0 90)
			(size 3.6576 3.6576)
			(layers "F.Cu" "F.Mask" "F.Paste")
			(net "GND")
		)
	)
)
